# S9S_MB_2U (Grand Teton) — schematic netlist excerpt (pin names and nets, part order shuffled) for the footprints in the layout excerpt that follows; sources: Cadence DE-HDL packaged netlist, KiCad conversion of 03242023_DA0F0TMBIJ0_F0T_Motherboard_J_brd_V01_OCP.brd

C609  Q_CAP  0.1UF 25V 10% X7R  pkg 0402  page 179 : A = RTC_EXT_CAP ; B = GND
R3132  Q_RES  100K 1% CHIP  pkg 0402LF  page 153 : A = GND ; B = FM_OCP_SFF_PWR_GOOD

(kicad_pcb
	(version 20260206)
	(generator "pcbnew")
	(generator_version "10.0")
	(general
		(thickness 1.6)
		(legacy_teardrops no)
	)
	(paper "A4")
	(title_block
		(title "03242023_DA0F0TMBIJ0_F0T_Motherboard_J_brd_V01_OCP.brd")
		(comment 1 "Grand Teton / footprints 2946-2947 of 6105")
	)
	(layers
		(0 "F.Cu" signal "TOP")
		(4 "In1.Cu" signal "GND")
		(6 "In2.Cu" signal "IN1")
		(8 "In3.Cu" signal "GND1")
		(10 "In4.Cu" signal "IN2")
		(12 "In5.Cu" signal "GND2")
		(14 "In6.Cu" signal "IN3")
		(16 "In7.Cu" signal "GND3")
		(18 "In8.Cu" signal "VCC")
		(20 "In9.Cu" signal "VCC1")
		(22 "In10.Cu" signal "GND4")
		(24 "In11.Cu" signal "IN4")
		(26 "In12.Cu" signal "GND5")
		(28 "In13.Cu" signal "IN5")
		(30 "In14.Cu" signal "GND6")
		(32 "In15.Cu" signal "IN6")
		(34 "In16.Cu" signal "GND7")
		(2 "B.Cu" signal "BOTTOM")
		(9 "F.Adhes" user "F.Adhesive")
		(11 "B.Adhes" user "B.Adhesive")
		(13 "F.Paste" user "Package Geometry/Pastemask Top")
		(15 "B.Paste" user "Package Geometry/Pastemask Bottom")
		(5 "F.SilkS" user "Ref Des/Silkscreen Top")
		(7 "B.SilkS" user "Ref Des/Silkscreen Bottom")
		(1 "F.Mask" user "Board Geometry/Soldermask Top")
		(3 "B.Mask" user "Board Geometry/Soldermask Bottom")
		(17 "Dwgs.User" user "User.Drawings")
		(19 "Cmts.User" user "User.Comments")
		(21 "Eco1.User" user "User.Eco1")
		(23 "Eco2.User" user "User.Eco2")
		(25 "Edge.Cuts" user "Board Geometry/Outline")
		(27 "Margin" user)
		(31 "F.CrtYd" user "Package Geometry/Place Bound Top")
		(29 "B.CrtYd" user "Package Geometry/Place Bound Bottom")
		(35 "F.Fab" user "Ref Des/Assembly Top")
		(33 "B.Fab" user "Ref Des/Assembly Bottom")
	)
	(footprint ""
		(layer "F.Cu")
		(at 322.349622 -33.848548 -135)
		(property "Reference" "C609"
			(at 0 0 225)
			(layer "F.SilkS")
			(hide yes)
			(effects
				(font
					(size 1.27 1.27)
				)
			)
		)
		(property "Value" ""
			(at 0 0 225)
			(layer "F.Fab")
			(effects
				(font
					(size 1.27 1.27)
				)
			)
		)
		(duplicate_pad_numbers_are_jumpers no)
		(fp_line
			(start 0.787389 0.406267)
			(end -0.787389 0.406267)
			(stroke
				(width 0.1524)
				(type default)
			)
			(layer "F.SilkS")
		)
		(fp_line
			(start 0.787389 -0.406267)
			(end 0.787389 0.406267)
			(stroke
				(width 0.1524)
				(type default)
			)
			(layer "F.SilkS")
		)
		(fp_line
			(start -0.787389 0.406267)
			(end -0.787389 -0.406267)
			(stroke
				(width 0.1524)
				(type default)
			)
			(layer "F.SilkS")
		)
		(fp_line
			(start -0.787389 -0.406267)
			(end 0.787389 -0.406267)
			(stroke
				(width 0.1524)
				(type default)
			)
			(layer "F.SilkS")
		)
		(fp_line
			(start 0.679446 0.30479)
			(end 0.120515 0.30479)
			(stroke
				(width 0.1)
				(type default)
			)
			(layer "F.Fab")
		)
		(fp_line
			(start 0.120515 0.30479)
			(end 0.120335 0.279466)
			(stroke
				(width 0.1)
				(type default)
			)
			(layer "F.Fab")
		)
		(fp_line
			(start 0.120335 0.279466)
			(end -0.120695 0.279466)
			(stroke
				(width 0.1)
				(type default)
			)
			(layer "F.Fab")
		)
		(fp_line
			(start 0.679446 -0.30479)
			(end 0.679446 0.30479)
			(stroke
				(width 0.1)
				(type default)
			)
			(layer "F.Fab")
		)
		(fp_line
			(start -0.120515 0.30479)
			(end -0.679446 0.30479)
			(stroke
				(width 0.1)
				(type default)
			)
			(layer "F.Fab")
		)
		(fp_line
			(start -0.120695 0.279466)
			(end -0.120515 0.30479)
			(stroke
				(width 0.1)
				(type default)
			)
			(layer "F.Fab")
		)
		(fp_line
			(start 0.120695 -0.279466)
			(end 0.120515 -0.30479)
			(stroke
				(width 0.1)
				(type default)
			)
			(layer "F.Fab")
		)
		(fp_line
			(start 0.120515 -0.30479)
			(end 0.679446 -0.30479)
			(stroke
				(width 0.1)
				(type default)
			)
			(layer "F.Fab")
		)
		(fp_line
			(start -0.679446 0.30479)
			(end -0.679446 -0.305149)
			(stroke
				(width 0.1)
				(type default)
			)
			(layer "F.Fab")
		)
		(fp_line
			(start -0.120695 -0.279466)
			(end 0.120695 -0.279466)
			(stroke
				(width 0.1)
				(type default)
			)
			(layer "F.Fab")
		)
		(fp_line
			(start -0.120695 -0.304969)
			(end -0.120695 -0.279466)
			(stroke
				(width 0.1)
				(type default)
			)
			(layer "F.Fab")
		)
		(fp_line
			(start -0.679446 -0.305149)
			(end -0.120695 -0.304969)
			(stroke
				(width 0.1)
				(type default)
			)
			(layer "F.Fab")
		)
		(pad "1" smd circle
			(at -0.40005 0 225)
			(size 0 0)
			(layers "F.Cu" "F.Mask" "F.Paste")
			(net "RTC_EXT_CAP")
		)
		(pad "2" smd circle
			(at 0.40005 0 225)
			(size 0 0)
			(layers "F.Cu" "F.Mask" "F.Paste")
			(net "GND")
		)
	)
	(footprint ""
		(layer "F.Cu")
		(at 160.838642 -110.9091)
		(property "Reference" "R3132"
			(at 0 0 0)
			(layer "F.SilkS")
			(hide yes)
			(effects
				(font
					(size 1.27 1.27)
				)
			)
		)
		(property "Value" ""
			(at 0 0 0)
			(layer "F.Fab")
			(effects
				(font
					(size 1.27 1.27)
				)
			)
		)
		(duplicate_pad_numbers_are_jumpers no)
		(fp_line
			(start -0.7874 -0.4064)
			(end 0.7874 -0.4064)
			(stroke
				(width 0.1524)
				(type default)
			)
			(layer "F.SilkS")
		)
		(fp_line
			(start -0.7874 0.4064)
			(end -0.7874 -0.4064)
			(stroke
				(width 0.1524)
				(type default)
			)
			(layer "F.SilkS")
		)
		(fp_line
			(start 0.7874 -0.4064)
			(end 0.7874 0.4064)
			(stroke
				(width 0.1524)
				(type default)
			)
			(layer "F.SilkS")
		)
		(fp_line
			(start 0.7874 0.4064)
			(end -0.7874 0.4064)
			(stroke
				(width 0.1524)
				(type default)
			)
			(layer "F.SilkS")
		)
		(fp_line
			(start -0.67945 -0.305054)
			(end -0.12065 -0.305054)
			(stroke
				(width 0.1)
				(type default)
			)
			(layer "F.Fab")
		)
		(fp_line
			(start -0.67945 0.3048)
			(end -0.67945 -0.305054)
			(stroke
				(width 0.1)
				(type default)
			)
			(layer "F.Fab")
		)
		(fp_line
			(start -0.12065 -0.305054)
			(end -0.12065 -0.2794)
			(stroke
				(width 0.1)
				(type default)
			)
			(layer "F.Fab")
		)
		(fp_line
			(start -0.12065 -0.2794)
			(end 0.12065 -0.2794)
			(stroke
				(width 0.1)
				(type default)
			)
			(layer "F.Fab")
		)
		(fp_line
			(start -0.12065 0.2794)
			(end -0.12065 0.3048)
			(stroke
				(width 0.1)
				(type default)
			)
			(layer "F.Fab")
		)
		(fp_line
			(start -0.12065 0.3048)
			(end -0.67945 0.3048)
			(stroke
				(width 0.1)
				(type default)
			)
			(layer "F.Fab")
		)
		(fp_line
			(start 0.120396 0.2794)
			(end -0.12065 0.2794)
			(stroke
				(width 0.1)
				(type default)
			)
			(layer "F.Fab")
		)
		(fp_line
			(start 0.120396 0.3048)
			(end 0.120396 0.2794)
			(stroke
				(width 0.1)
				(type default)
			)
			(layer "F.Fab")
		)
		(fp_line
			(start 0.12065 -0.3048)
			(end 0.67945 -0.3048)
			(stroke
				(width 0.1)
				(type default)
			)
			(layer "F.Fab")
		)
		(fp_line
			(start 0.12065 -0.2794)
			(end 0.12065 -0.3048)
			(stroke
				(width 0.1)
				(type default)
			)
			(layer "F.Fab")
		)
		(fp_line
			(start 0.67945 -0.3048)
			(end 0.67945 0.3048)
			(stroke
				(width 0.1)
				(type default)
			)
			(layer "F.Fab")
		)
		(fp_line
			(start 0.67945 0.3048)
			(end 0.120396 0.3048)
			(stroke
				(width 0.1)
				(type default)
			)
			(layer "F.Fab")
		)
		(pad "1" smd circle
			(at -0.40005 0)
			(size 0 0)
			(layers "F.Cu" "F.Mask" "F.Paste")
			(net "GND")
		)
		(pad "2" smd circle
			(at 0.40005 0)
			(size 0 0)
			(layers "F.Cu" "F.Mask" "F.Paste")
			(net "FM_OCP_SFF_PWR_GOOD")
		)
	)
)
